# T6G (Grand Teton) — schematic netlist excerpt (pin names and nets, part order shuffled) for the footprints in the layout excerpt that follows; sources: Cadence DE-HDL packaged netlist, KiCad conversion of 04192023_DAF0TMB3IC0_F0TG_MB_C_brd_V02_OCP.brd

J33  SCONN288_DDR506112002KQ  IO  pkg DDR288S_1-1VXC  page 103
  VIN_BULK0  = P12V_MEM_CPU1
  RFU0  = NC
  VIN_MGMT  = P3V3_AUX
  HSCL  = I3C_SPD_DDRF_CPU1_SCL
  HSDA  = I3C_SPD_DDRF_CPU1_SDA
  VSS0  = GND
  DQ0_A  = M_F_CPU1_SA_DQ<0>
  VSS1  = GND
  DQ1_A  = M_F_CPU1_SA_DQ<1>
  VSS2  = GND
  DQS0_A_T  = M_F_CPU1_SA_DQS_DP<0>
  DQS0_A_C  = M_F_CPU1_SA_DQS_DN<0>
  VSS3  = GND
  DQ4_A  = M_F_CPU1_SA_DQ<4>
  VSS4  = GND
  DQ5_A  = M_F_CPU1_SA_DQ<5>
  VSS5  = GND
  DQ8_A  = M_F_CPU1_SA_DQ<8>
  VSS6  = GND
  DQ9_A  = M_F_CPU1_SA_DQ<9>
  VSS7  = GND
  DQS1_A_T  = M_F_CPU1_SA_DQS_DP<1>
  DQS1_A_C  = M_F_CPU1_SA_DQS_DN<1>
  VSS8  = GND
  DQ12_A  = M_F_CPU1_SA_DQ<12>
  VSS9  = GND
  DQ13_A  = M_F_CPU1_SA_DQ<13>
  VSS10  = GND
  DQ16_A  = M_F_CPU1_SA_DQ<16>
  VSS11  = GND
  DQ17_A  = M_F_CPU1_SA_DQ<17>
  VSS12  = GND
  DQS2_A_T  = M_F_CPU1_SA_DQS_DP<2>
  DQS2_A_C  = M_F_CPU1_SA_DQS_DN<2>
  VSS13  = GND
  DQ20_A  = M_F_CPU1_SA_DQ<20>
  VSS14  = GND
  DQ21_A  = M_F_CPU1_SA_DQ<21>
  VSS15  = GND
  DQ24_A  = M_F_CPU1_SA_DQ<24>
  VSS16  = GND
  DQ25_A  = M_F_CPU1_SA_DQ<25>
  VSS17  = GND
  DQS3_A_T  = M_F_CPU1_SA_DQS_DP<3>
  DQS3_A_C  = M_F_CPU1_SA_DQS_DN<3>
  VSS18  = GND
  DQ28_A  = M_F_CPU1_SA_DQ<28>
  VSS19  = GND
  DQ29_A  = M_F_CPU1_SA_DQ<29>
  VSS20  = GND
  CB0_A  = M_F_CPU1_SA_CB<0>
  VSS21  = GND
  CB1_A  = M_F_CPU1_SA_CB<1>
  VSS22  = GND
  DQS4_A_T  = M_F_CPU1_SA_DQS_DP<4>
  DQS4_A_C  = M_F_CPU1_SA_DQS_DN<4>
  VSS23  = GND
  CB4_A  = M_F_CPU1_SA_CB<4>
  VSS24  = GND
  CB5_A  = M_F_CPU1_SA_CB<5>
  VSS25  = GND
  ALERT_N  = M_F_CPU1_ALERT_N
  VSS26  = GND
  CS0_A_N  = M_F_CPU1_SA_CS_N<0>
  VSS27  = GND
  CA0_A  = M_F_CPU1_SA_CA<0>
  VSS28  = GND
  CA2_A  = M_F_CPU1_SA_CA<2>
  VSS29  = GND
  CA4_A  = M_F_CPU1_SA_CA<4>
  VSS30  = GND
  CA6_A  = M_F_CPU1_SA_CA<6>
  VSS31  = GND
  PAR_A  = M_F_CPU1_SA_PAR
  VSS32  = GND
  CA0_B  = M_F_CPU1_SB_CA<0>
  VSS33  = GND
  CA2_B  = M_F_CPU1_SB_CA<2>
  VSS34  = GND
  CA4_B  = M_F_CPU1_SB_CA<4>
  VSS35  = GND
  CA6_B  = M_F_CPU1_SB_CA<6>
  VSS36  = GND
  CS0_B_N  = M_F_CPU1_SB_CS_N<0>
  VSS37  = GND
  \lbd||rsp_a_n\  = M_F_CPU1_SA_RSP<0>
  \lbs||rsp_b_n\  = M_F_CPU1_SB_RSP<0>
  VSS38  = GND
  CB4_B  = M_F_CPU1_SB_CB<4>
  VSS39  = GND
  CB5_B  = M_F_CPU1_SB_CB<5>
  VSS40  = GND
  \dqs9_b_t||tdqs9_b_t||dbi4_b_n\  = M_F_CPU1_SB_DQS_DP<9>
  \dqs9_b_c||tdqs9_b_c\  = M_F_CPU1_SB_DQS_DN<9>
  VSS41  = GND
  CB0_B  = M_F_CPU1_SB_CB<0>
  VSS42  = GND
  CB1_B  = M_F_CPU1_SB_CB<1>
  VSS43  = GND
  DQ0_B  = M_F_CPU1_SB_DQ<0>
  VSS44  = GND
  DQ1_B  = M_F_CPU1_SB_DQ<1>
  VSS45  = GND
  DQS0_B_T  = M_F_CPU1_SB_DQS_DP<0>
  DQS0_B_C  = M_F_CPU1_SB_DQS_DN<0>
  VSS46  = GND
  DQ4_B  = M_F_CPU1_SB_DQ<4>
  VSS47  = GND
  DQ5_B  = M_F_CPU1_SB_DQ<5>
  VSS48  = GND
  DQ8_B  = M_F_CPU1_SB_DQ<8>
  VSS49  = GND
  DQ9_B  = M_F_CPU1_SB_DQ<9>
  VSS50  = GND
  DQS1_B_T  = M_F_CPU1_SB_DQS_DP<1>
  DQS1_B_C  = M_F_CPU1_SB_DQS_DN<1>
  VSS51  = GND
  DQ12_B  = M_F_CPU1_SB_DQ<12>
  VSS52  = GND
  DQ13_B  = M_F_CPU1_SB_DQ<13>
  VSS53  = GND
  DQ16_B  = M_F_CPU1_SB_DQ<16>
  VSS54  = GND
  DQ17_B  = M_F_CPU1_SB_DQ<17>
  VSS55  = GND
  DQS2_B_T  = M_F_CPU1_SB_DQS_DP<2>
  DQS2_B_C  = M_F_CPU1_SB_DQS_DN<2>
  VSS56  = GND
  DQ20_B  = M_F_CPU1_SB_DQ<20>
  VSS57  = GND
  DQ21_B  = M_F_CPU1_SB_DQ<21>
  VSS58  = GND
  DQ24_B  = M_F_CPU1_SB_DQ<24>
  VSS59  = GND
  DQ25_B  = M_F_CPU1_SB_DQ<25>
  VSS60  = GND
  DQS3_B_T  = M_F_CPU1_SB_DQS_DP<3>
  DQS3_B_C  = M_F_CPU1_SB_DQS_DN<3>
  VSS61  = GND
  DQ28_B  = M_F_CPU1_SB_DQ<28>
  VSS62  = GND
  DQ29_B  = M_F_CPU1_SB_DQ<29>
  VSS63  = GND
  RFU1  = NC
  VIN_BULK1  = P12V_MEM_CPU1
  VIN_BULK2  = P12V_MEM_CPU1
  \pwr_good||fail_n\  = PWRGD_CHF_CPU1_DIMM
  HAS  = PD_CHF_CPU1_DIMM_SAA
  RFU2  = NC
  RFU3  = NC
  VSS64  = GND
  DQ2_A  = M_F_CPU1_SA_DQ<2>
  VSS65  = GND
  DQ3_A  = M_F_CPU1_SA_DQ<3>
  VSS66  = GND
  \dqs5_a_c||tdqs5_a_c||dqs5_a_t||tdqs5_a_t\  = M_F_CPU1_SA_DQS_DN<5>
  \dqs5_a_t||tdqs5_a_t\  = M_F_CPU1_SA_DQS_DP<5>
  VSS67  = GND
  DQ6_A  = M_F_CPU1_SA_DQ<6>
  VSS68  = GND
  DQ7_A  = M_F_CPU1_SA_DQ<7>
  VSS69  = GND
  DQ10_A  = M_F_CPU1_SA_DQ<10>
  VSS70  = GND
  DQ11_A  = M_F_CPU1_SA_DQ<11>
  VSS71  = GND
  \dqs6_a_c||tdqs6_a_c||dqs6_a_t||tdqs6_a_t\  = M_F_CPU1_SA_DQS_DN<6>
  \dqs6_a_t||tdqs6_a_t\  = M_F_CPU1_SA_DQS_DP<6>
  VSS72  = GND
  DQ14_A  = M_F_CPU1_SA_DQ<14>
  VSS73  = GND
  DQ15_A  = M_F_CPU1_SA_DQ<15>
  VSS74  = GND
  DQ18_A  = M_F_CPU1_SA_DQ<18>
  VSS75  = GND
  DQ19_A  = M_F_CPU1_SA_DQ<19>
  VSS76  = GND
  \dqs7_a_c||tdqs7_a_c\  = M_F_CPU1_SA_DQS_DN<7>
  \dqs7_a_t||tdqs7_a_t\  = M_F_CPU1_SA_DQS_DP<7>
  VSS77  = GND
  DQ22_A  = M_F_CPU1_SA_DQ<22>
  VSS78  = GND
  DQ23_A  = M_F_CPU1_SA_DQ<23>
  VSS79  = GND
  DQ26_A  = M_F_CPU1_SA_DQ<26>
  VSS80  = GND
  DQ27_A  = M_F_CPU1_SA_DQ<27>
  VSS81  = GND
  \dqs8_a_c||tdqs8_a_c\  = M_F_CPU1_SA_DQS_DN<8>
  \dqs8_a_t||tdqs8_a_t\  = M_F_CPU1_SA_DQS_DP<8>
  VSS82  = GND
  DQ30_A  = M_F_CPU1_SA_DQ<30>
  VSS83  = GND
  DQ31_A  = M_F_CPU1_SA_DQ<31>
  VSS84  = GND
  CB2_A  = M_F_CPU1_SA_CB<2>
  VSS85  = GND
  CB3_A  = M_F_CPU1_SA_CB<3>
  VSS86  = GND
  \dqs9_a_c||tdqs9_a_c\  = M_F_CPU1_SA_DQS_DN<9>
  \dqs9_a_t||tdqs9_a_t\  = M_F_CPU1_SA_DQS_DP<9>
  VSS87  = GND
  CB6_A  = M_F_CPU1_SA_CB<6>
  VSS88  = GND
  CB7_A  = M_F_CPU1_SA_CB<7>
  VSS89  = GND
  RESET_N  = M_F_CPU1_RESET_N
  VSS90  = GND
  CS1_A_N  = M_F_CPU1_SA_CS_N<1>
  VSS91  = GND
  CA1_A  = M_F_CPU1_SA_CA<1>
  VSS92  = GND
  CA3_A  = M_F_CPU1_SA_CA<3>
  VSS93  = GND
  CA5_A  = M_F_CPU1_SA_CA<5>
  VSS94  = GND
  CK_T  = M_F_CPU1_CLK_DP<0>
  CK_C  = M_F_CPU1_CLK_DN<0>
  VSS95  = GND
  RFU4  = NC
  CA1_B  = M_F_CPU1_SB_CA<1>
  VSS96  = GND
  CA3_B  = M_F_CPU1_SB_CA<3>
  VSS97  = GND
  CA5_B  = M_F_CPU1_SB_CA<5>
  VSS98  = GND
  PAR_B  = M_F_CPU1_SB_PAR
  VSS99  = GND
  CS1_B_N  = M_F_CPU1_SB_CS_N<1>
  VSS100  = GND
  RFU5  = NC
  RFU6  = NC
  VSS101  = GND
  CB6_B  = M_F_CPU1_SB_CB<6>
  VSS102  = GND
  CB7_B  = M_F_CPU1_SB_CB<7>
  VSS103  = GND
  DQS4_B_C  = M_F_CPU1_SB_DQS_DN<4>
  DQS4_B_T  = M_F_CPU1_SB_DQS_DP<4>
  VSS104  = GND
  CB2_B  = M_F_CPU1_SB_CB<2>
  VSS105  = GND
  CB3_B  = M_F_CPU1_SB_CB<3>
  VSS106  = GND
  DQ2_B  = M_F_CPU1_SB_DQ<2>
  VSS107  = GND
  DQ3_B  = M_F_CPU1_SB_DQ<3>
  VSS108  = GND
  \dqs5_b_c||tdqs5_b_c\  = M_F_CPU1_SB_DQS_DN<5>
  \dqs5_b_t||tdqs5_b_t\  = M_F_CPU1_SB_DQS_DP<5>
  VSS109  = GND
  DQ6_B  = M_F_CPU1_SB_DQ<6>
  VSS110  = GND
  DQ7_B  = M_F_CPU1_SB_DQ<7>
  VSS111  = GND
  DQ10_B  = M_F_CPU1_SB_DQ<10>
  VSS112  = GND
  DQ11_B  = M_F_CPU1_SB_DQ<11>
  VSS113  = GND
  \dqs6_b_c||tdqs6_b_c\  = M_F_CPU1_SB_DQS_DN<6>
  \dqs6_b_t||tdqs6_b_t\  = M_F_CPU1_SB_DQS_DP<6>
  VSS114  = GND
  DQ14_B  = M_F_CPU1_SB_DQ<14>
  VSS115  = GND
  DQ15_B  = M_F_CPU1_SB_DQ<15>
  VSS116  = GND
  DQ18_B  = M_F_CPU1_SB_DQ<18>
  VSS117  = GND
  DQ19_B  = M_F_CPU1_SB_DQ<19>
  VSS118  = GND
  \dqs7_b_c||tdqs7_b_c\  = M_F_CPU1_SB_DQS_DN<7>
  \dqs7_b_t||tdqs7_b_t\  = M_F_CPU1_SB_DQS_DP<7>
  VSS119  = GND
  DQ22_B  = M_F_CPU1_SB_DQ<22>
  VSS120  = GND
  DQ23_B  = M_F_CPU1_SB_DQ<23>
  VSS121  = GND
  DQ26_B  = M_F_CPU1_SB_DQ<26>
  VSS122  = GND
  DQ27_B  = M_F_CPU1_SB_DQ<27>
  VSS123  = GND
  \dqs8_b_c||tdqs8_b_c\  = M_F_CPU1_SB_DQS_DN<8>
  \dqs8_b_t||tdqs8_b_t\  = M_F_CPU1_SB_DQS_DP<8>
  VSS124  = GND
  DQ30_B  = M_F_CPU1_SB_DQ<30>
  VSS125  = GND
  DQ31_B  = M_F_CPU1_SB_DQ<31>
  VSS126  = GND
  G1  = GND
  G2  = GND
  G3  = GND

(kicad_pcb
	(version 20260206)
	(generator "pcbnew")
	(generator_version "10.0")
	(general
		(thickness 1.6)
		(legacy_teardrops no)
	)
	(paper "A4")
	(title_block
		(title "04192023_DAF0TMB3IC0_F0TG_MB_C_brd_V02_OCP.brd")
		(comment 1 "Grand Teton / footprint 4248 of 8354 (J33), pads 1-46 of 291")
	)
	(layers
		(0 "F.Cu" signal "TOP")
		(4 "In1.Cu" signal "GND")
		(6 "In2.Cu" signal "IN1")
		(8 "In3.Cu" signal "GND1")
		(10 "In4.Cu" signal "IN2")
		(12 "In5.Cu" signal "GND2")
		(14 "In6.Cu" signal "IN3")
		(16 "In7.Cu" signal "GND3")
		(18 "In8.Cu" signal "VCC")
		(20 "In9.Cu" signal "VCC1")
		(22 "In10.Cu" signal "GND4")
		(24 "In11.Cu" signal "IN4")
		(26 "In12.Cu" signal "GND5")
		(28 "In13.Cu" signal "IN5")
		(30 "In14.Cu" signal "GND6")
		(32 "In15.Cu" signal "IN6")
		(34 "In16.Cu" signal "GND7")
		(2 "B.Cu" signal "BOTTOM")
		(9 "F.Adhes" user "F.Adhesive")
		(11 "B.Adhes" user "B.Adhesive")
		(13 "F.Paste" user "Package Geometry/Pastemask Top")
		(15 "B.Paste" user "Package Geometry/Pastemask Bottom")
		(5 "F.SilkS" user "Ref Des/Silkscreen Top")
		(7 "B.SilkS" user "Ref Des/Silkscreen Bottom")
		(1 "F.Mask" user "Board Geometry/Soldermask Top")
		(3 "B.Mask" user "Board Geometry/Soldermask Bottom")
		(17 "Dwgs.User" user "User.Drawings")
		(19 "Cmts.User" user "User.Comments")
		(21 "Eco1.User" user "User.Eco1")
		(23 "Eco2.User" user "User.Eco2")
		(25 "Edge.Cuts" user "Board Geometry/Outline")
		(27 "Margin" user)
		(31 "F.CrtYd" user "Package Geometry/Place Bound Top")
		(29 "B.CrtYd" user "Package Geometry/Place Bound Bottom")
		(35 "F.Fab" user "Ref Des/Assembly Top")
		(33 "B.Fab" user "Ref Des/Assembly Bottom")
	)
	(footprint ""
		(layer "F.Cu")
		(at 19.658076 -255.560322 180)
		(property "Reference" "J33"
			(at -1.25984 -82.079846 0)
			(unlocked yes)
			(layer "F.SilkS")
			(effects
				(font
					(size 0.7874 0.5842)
					(thickness 0.1524)
				)
			)
		)
		(property "Value" ""
			(at 0 0 180)
			(layer "F.Fab")
			(effects
				(font
					(size 1.27 1.27)
				)
			)
		)
		(duplicate_pad_numbers_are_jumpers no)
		(pad "1" smd rect
			(at -2.050034 -63.324994 90)
			(size 0.519938 1.4986)
			(layers "F.Cu" "F.Mask" "F.Paste")
			(net "P12V_MEM_CPU1")
		)
		(pad "2" smd rect
			(at -2.050034 -62.47511 90)
			(size 0.519938 1.4986)
			(layers "F.Cu" "F.Mask" "F.Paste")
			(net "Net_2326")
		)
		(pad "3" smd rect
			(at -2.050034 -61.624972 90)
			(size 0.519938 1.4986)
			(layers "F.Cu" "F.Mask" "F.Paste")
			(net "P3V3_AUX")
		)
		(pad "4" smd rect
			(at -2.050034 -60.775088 90)
			(size 0.519938 1.4986)
			(layers "F.Cu" "F.Mask" "F.Paste")
			(net "I3C_SPD_DDRF_CPU1_SCL")
		)
		(pad "5" smd rect
			(at -2.050034 -59.92495 90)
			(size 0.519938 1.4986)
			(layers "F.Cu" "F.Mask" "F.Paste")
			(net "I3C_SPD_DDRF_CPU1_SDA")
		)
		(pad "6" smd rect
			(at -2.050034 -59.075066 90)
			(size 0.519938 1.4986)
			(layers "F.Cu" "F.Mask" "F.Paste")
			(net "GND")
		)
		(pad "7" smd rect
			(at -2.050034 -58.224928 90)
			(size 0.519938 1.4986)
			(layers "F.Cu" "F.Mask" "F.Paste")
			(net "M_F_CPU1_SA_DQ<0>")
		)
		(pad "8" smd rect
			(at -2.050034 -57.375044 90)
			(size 0.519938 1.4986)
			(layers "F.Cu" "F.Mask" "F.Paste")
			(net "GND")
		)
		(pad "9" smd rect
			(at -2.050034 -56.524906 90)
			(size 0.519938 1.4986)
			(layers "F.Cu" "F.Mask" "F.Paste")
			(net "M_F_CPU1_SA_DQ<1>")
		)
		(pad "10" smd rect
			(at -2.050034 -55.675022 90)
			(size 0.519938 1.4986)
			(layers "F.Cu" "F.Mask" "F.Paste")
			(net "GND")
		)
		(pad "11" smd rect
			(at -2.050034 -54.824884 90)
			(size 0.519938 1.4986)
			(layers "F.Cu" "F.Mask" "F.Paste")
			(net "M_F_CPU1_SA_DQS_DP<0>")
		)
		(pad "12" smd rect
			(at -2.050034 -53.975 90)
			(size 0.519938 1.4986)
			(layers "F.Cu" "F.Mask" "F.Paste")
			(net "M_F_CPU1_SA_DQS_DN<0>")
		)
		(pad "13" smd rect
			(at -2.050034 -53.125116 90)
			(size 0.519938 1.4986)
			(layers "F.Cu" "F.Mask" "F.Paste")
			(net "GND")
		)
		(pad "14" smd rect
			(at -2.050034 -52.274978 90)
			(size 0.519938 1.4986)
			(layers "F.Cu" "F.Mask" "F.Paste")
			(net "M_F_CPU1_SA_DQ<4>")
		)
		(pad "15" smd rect
			(at -2.050034 -51.425094 90)
			(size 0.519938 1.4986)
			(layers "F.Cu" "F.Mask" "F.Paste")
			(net "GND")
		)
		(pad "16" smd rect
			(at -2.050034 -50.574956 90)
			(size 0.519938 1.4986)
			(layers "F.Cu" "F.Mask" "F.Paste")
			(net "M_F_CPU1_SA_DQ<5>")
		)
		(pad "17" smd rect
			(at -2.050034 -49.725072 90)
			(size 0.519938 1.4986)
			(layers "F.Cu" "F.Mask" "F.Paste")
			(net "GND")
		)
		(pad "18" smd rect
			(at -2.050034 -48.874934 90)
			(size 0.519938 1.4986)
			(layers "F.Cu" "F.Mask" "F.Paste")
			(net "M_F_CPU1_SA_DQ<8>")
		)
		(pad "19" smd rect
			(at -2.050034 -48.02505 90)
			(size 0.519938 1.4986)
			(layers "F.Cu" "F.Mask" "F.Paste")
			(net "GND")
		)
		(pad "20" smd rect
			(at -2.050034 -47.174912 90)
			(size 0.519938 1.4986)
			(layers "F.Cu" "F.Mask" "F.Paste")
			(net "M_F_CPU1_SA_DQ<9>")
		)
		(pad "21" smd rect
			(at -2.050034 -46.325028 90)
			(size 0.519938 1.4986)
			(layers "F.Cu" "F.Mask" "F.Paste")
			(net "GND")
		)
		(pad "22" smd rect
			(at -2.050034 -45.47489 90)
			(size 0.519938 1.4986)
			(layers "F.Cu" "F.Mask" "F.Paste")
			(net "M_F_CPU1_SA_DQS_DP<1>")
		)
		(pad "23" smd rect
			(at -2.050034 -44.625006 90)
			(size 0.519938 1.4986)
			(layers "F.Cu" "F.Mask" "F.Paste")
			(net "M_F_CPU1_SA_DQS_DN<1>")
		)
		(pad "24" smd rect
			(at -2.050034 -43.775122 90)
			(size 0.519938 1.4986)
			(layers "F.Cu" "F.Mask" "F.Paste")
			(net "GND")
		)
		(pad "25" smd rect
			(at -2.050034 -42.924984 90)
			(size 0.519938 1.4986)
			(layers "F.Cu" "F.Mask" "F.Paste")
			(net "M_F_CPU1_SA_DQ<12>")
		)
		(pad "26" smd rect
			(at -2.050034 -42.0751 90)
			(size 0.519938 1.4986)
			(layers "F.Cu" "F.Mask" "F.Paste")
			(net "GND")
		)
		(pad "27" smd rect
			(at -2.050034 -41.224962 90)
			(size 0.519938 1.4986)
			(layers "F.Cu" "F.Mask" "F.Paste")
			(net "M_F_CPU1_SA_DQ<13>")
		)
		(pad "28" smd rect
			(at -2.050034 -40.375078 90)
			(size 0.519938 1.4986)
			(layers "F.Cu" "F.Mask" "F.Paste")
			(net "GND")
		)
		(pad "29" smd rect
			(at -2.050034 -39.52494 90)
			(size 0.519938 1.4986)
			(layers "F.Cu" "F.Mask" "F.Paste")
			(net "M_F_CPU1_SA_DQ<16>")
		)
		(pad "30" smd rect
			(at -2.050034 -38.675056 90)
			(size 0.519938 1.4986)
			(layers "F.Cu" "F.Mask" "F.Paste")
			(net "GND")
		)
		(pad "31" smd rect
			(at -2.050034 -37.824918 90)
			(size 0.519938 1.4986)
			(layers "F.Cu" "F.Mask" "F.Paste")
			(net "M_F_CPU1_SA_DQ<17>")
		)
		(pad "32" smd rect
			(at -2.050034 -36.975034 90)
			(size 0.519938 1.4986)
			(layers "F.Cu" "F.Mask" "F.Paste")
			(net "GND")
		)
		(pad "33" smd rect
			(at -2.050034 -36.124896 90)
			(size 0.519938 1.4986)
			(layers "F.Cu" "F.Mask" "F.Paste")
			(net "M_F_CPU1_SA_DQS_DP<2>")
		)
		(pad "34" smd rect
			(at -2.050034 -35.275012 90)
			(size 0.519938 1.4986)
			(layers "F.Cu" "F.Mask" "F.Paste")
			(net "M_F_CPU1_SA_DQS_DN<2>")
		)
		(pad "35" smd rect
			(at -2.050034 -34.425128 90)
			(size 0.519938 1.4986)
			(layers "F.Cu" "F.Mask" "F.Paste")
			(net "GND")
		)
		(pad "36" smd rect
			(at -2.050034 -33.57499 90)
			(size 0.519938 1.4986)
			(layers "F.Cu" "F.Mask" "F.Paste")
			(net "M_F_CPU1_SA_DQ<20>")
		)
		(pad "37" smd rect
			(at -2.050034 -32.725106 90)
			(size 0.519938 1.4986)
			(layers "F.Cu" "F.Mask" "F.Paste")
			(net "GND")
		)
		(pad "38" smd rect
			(at -2.050034 -31.874968 90)
			(size 0.519938 1.4986)
			(layers "F.Cu" "F.Mask" "F.Paste")
			(net "M_F_CPU1_SA_DQ<21>")
		)
		(pad "39" smd rect
			(at -2.050034 -31.025084 90)
			(size 0.519938 1.4986)
			(layers "F.Cu" "F.Mask" "F.Paste")
			(net "GND")
		)
		(pad "40" smd rect
			(at -2.050034 -30.174946 90)
			(size 0.519938 1.4986)
			(layers "F.Cu" "F.Mask" "F.Paste")
			(net "M_F_CPU1_SA_DQ<24>")
		)
		(pad "41" smd rect
			(at -2.050034 -29.325062 90)
			(size 0.519938 1.4986)
			(layers "F.Cu" "F.Mask" "F.Paste")
			(net "GND")
		)
		(pad "42" smd rect
			(at -2.050034 -28.474924 90)
			(size 0.519938 1.4986)
			(layers "F.Cu" "F.Mask" "F.Paste")
			(net "M_F_CPU1_SA_DQ<25>")
		)
		(pad "43" smd rect
			(at -2.050034 -27.62504 90)
			(size 0.519938 1.4986)
			(layers "F.Cu" "F.Mask" "F.Paste")
			(net "GND")
		)
		(pad "44" smd rect
			(at -2.050034 -26.774902 90)
			(size 0.519938 1.4986)
			(layers "F.Cu" "F.Mask" "F.Paste")
			(net "M_F_CPU1_SA_DQS_DP<3>")
		)
		(pad "45" smd rect
			(at -2.050034 -25.925018 90)
			(size 0.519938 1.4986)
			(layers "F.Cu" "F.Mask" "F.Paste")
			(net "M_F_CPU1_SA_DQS_DN<3>")
		)
		(pad "46" smd rect
			(at -2.050034 -25.07488 90)
			(size 0.519938 1.4986)
			(layers "F.Cu" "F.Mask" "F.Paste")
			(net "GND")
		)
	)
)
